# BASEBOARD_FAB2 (Tioga Pass) — schematic netlist excerpt (pin names and nets, part order shuffled) for the footprints in the layout excerpt that follows; sources: Cadence DE-HDL packaged netlist, KiCad conversion of Wiwynn_Tioga_Pass_MB.brd

EU1E2  IR354XX  IR35411 IC  pkg SM  page 207
  VOS  = PVCCIN_CPU1
  LGND  = GND
  VCC  = VR_PVCCIN_CPU1_PH1_VCIN
  VDRV  = P5V_STBY
  PGND(0)  = GND
  GL(0)  = TP_PVCCINC_CPU1_PH1_GL_0
  PGND(1)  = GND
  SW  = VR_PVCCIN_CPU1_PHASE1
  VIN(0)  = VR_FET_SW_P12V_STBY_PVCCIN_CPU1
  VIN(1)  = VR_FET_SW_P12V_STBY_PVCCIN_CPU1
  NC  = NC
  PHASE  = VR_PVCCIN_CPU1_PH1_PHASE
  BOOST  = VR_PVCCIN_CPU1_PH1_BOOT_R
  PWM  = VR_PVCCIN_CPU1_PWM1
  EN  = P5V_STBY
  TOUT_FLT  = A_TSENSE_PVCCIN_CPU1
  OCSET  = VR_PVCCIN_CPU1_PH1_OCSET
  IOUT  = ISENSE_PVCCIN_CPU1_PH1_IMON
  REFIN  = VR_PVCCIN_CPU1_AIREF1
  PGND(2)  = GND
  GL(1)  = TP_PVCCINC_CPU1_PH1_GL_1

(kicad_pcb
	(version 20260206)
	(generator "pcbnew")
	(generator_version "10.0")
	(general
		(thickness 1.6)
		(legacy_teardrops no)
	)
	(paper "A4")
	(title_block
		(title "Wiwynn_Tioga_Pass_MB.brd")
		(comment 1 "Tioga Pass / footprints 1527-1527 of 4770")
	)
	(layers
		(0 "F.Cu" signal "TOP")
		(4 "In1.Cu" signal "L2GND")
		(6 "In2.Cu" signal "L3")
		(8 "In3.Cu" signal "L4GND")
		(10 "In4.Cu" signal "L5")
		(12 "In5.Cu" signal "L6GND")
		(14 "In6.Cu" signal "L7VCC")
		(16 "In7.Cu" signal "L8VCC")
		(18 "In8.Cu" signal "L9GND")
		(20 "In9.Cu" signal "L10")
		(22 "In10.Cu" signal "L11GND")
		(24 "In11.Cu" signal "L12")
		(26 "In12.Cu" signal "L13GND")
		(2 "B.Cu" signal "BOTTOM")
		(9 "F.Adhes" user "F.Adhesive")
		(11 "B.Adhes" user "B.Adhesive")
		(13 "F.Paste" user "Package Geometry/Pastemask Top")
		(15 "B.Paste" user "Package Geometry/Pastemask Bottom")
		(5 "F.SilkS" user "Ref Des/Silkscreen Top")
		(7 "B.SilkS" user "Ref Des/Silkscreen Bottom")
		(1 "F.Mask" user "Board Geometry/Soldermask Top")
		(3 "B.Mask" user "Board Geometry/Soldermask Bottom")
		(17 "Dwgs.User" user "User.Drawings")
		(19 "Cmts.User" user "User.Comments")
		(21 "Eco1.User" user "User.Eco1")
		(23 "Eco2.User" user "User.Eco2")
		(25 "Edge.Cuts" user "Board Geometry/Outline")
		(27 "Margin" user)
		(31 "F.CrtYd" user "Package Geometry/Place Bound Top")
		(29 "B.CrtYd" user "Package Geometry/Place Bound Bottom")
		(35 "F.Fab" user "Ref Des/Assembly Top")
		(33 "B.Fab" user "Ref Des/Assembly Bottom")
	)
	(footprint ""
		(layer "F.Cu")
		(at 33.925002 -57.039764 90)
		(property "Reference" "EU1E2"
			(at 3.360166 -1.768602 0)
			(unlocked yes)
			(layer "F.SilkS")
			(effects
				(font
					(size 0.7874 0.5842)
					(thickness 0.1524)
				)
			)
		)
		(property "Value" ""
			(at 0 0 90)
			(layer "F.Fab")
			(effects
				(font
					(size 1.27 1.27)
				)
			)
		)
		(duplicate_pad_numbers_are_jumpers no)
		(fp_line
			(start 2.9718 -3.5052)
			(end 2.9718 3.429)
			(stroke
				(width 0.1524)
				(type default)
			)
			(layer "F.SilkS")
		)
		(fp_line
			(start -3.0099 -3.5052)
			(end 2.9718 -3.5052)
			(stroke
				(width 0.1524)
				(type default)
			)
			(layer "F.SilkS")
		)
		(fp_line
			(start 2.9718 3.429)
			(end -3.0099 3.429)
			(stroke
				(width 0.1524)
				(type default)
			)
			(layer "F.SilkS")
		)
		(fp_line
			(start -3.0099 3.429)
			(end -3.0099 -3.5052)
			(stroke
				(width 0.1524)
				(type default)
			)
			(layer "F.SilkS")
		)
		(fp_circle
			(center -3.057398 -2.678684)
			(end -3.057398 -2.551684)
			(stroke
				(width 0.254)
				(type default)
			)
			(fill no)
			(layer "F.SilkS")
		)
		(fp_poly
			(pts
				(xy -2.9972 -3.4925) (xy -2.9972 -2.6924) (xy -2.1971 -3.4925)
			)
			(stroke
				(width 0)
				(type default)
			)
			(fill yes)
			(layer "F.SilkS")
		)
		(fp_poly
			(pts
				(xy -2.549906 -3.050032) (xy -2.549906 3.050032) (xy 2.549906 3.050032) (xy 2.549906 -3.050032)
			)
			(stroke
				(width 0)
				(type default)
			)
			(fill no)
			(layer "F.CrtYd")
		)
		(fp_line
			(start 2.549906 -3.050032)
			(end 2.549906 3.050032)
			(stroke
				(width 0.1)
				(type default)
			)
			(layer "F.Fab")
		)
		(fp_line
			(start -2.549906 -3.050032)
			(end 2.549906 -3.050032)
			(stroke
				(width 0.1)
				(type default)
			)
			(layer "F.Fab")
		)
		(fp_line
			(start 2.549906 3.050032)
			(end -2.549906 3.050032)
			(stroke
				(width 0.1)
				(type default)
			)
			(layer "F.Fab")
		)
		(fp_line
			(start -2.549906 3.050032)
			(end -2.549906 -3.050032)
			(stroke
				(width 0.1)
				(type default)
			)
			(layer "F.Fab")
		)
		(fp_circle
			(center -3.057398 -2.678684)
			(end -3.057398 -2.551684)
			(stroke
				(width 0.254)
				(type default)
			)
			(fill no)
			(layer "F.Fab")
		)
		(pad "1" smd rect
			(at -2.39522 -2.279904 90)
			(size 0.7112 0.254)
			(layers "F.Cu" "F.Mask" "F.Paste")
			(net "PVCCIN_CPU1")
		)
		(pad "2" smd rect
			(at -2.39522 -1.83007 90)
			(size 0.7112 0.254)
			(layers "F.Cu" "F.Mask" "F.Paste")
			(net "GND")
		)
		(pad "3" smd rect
			(at -2.39522 -1.379982 90)
			(size 0.7112 0.254)
			(layers "F.Cu" "F.Mask" "F.Paste")
			(net "VR_PVCCIN_CPU1_PH1_VCIN")
		)
		(pad "4" smd rect
			(at -2.39522 -0.929894 90)
			(size 0.7112 0.254)
			(layers "F.Cu" "F.Mask" "F.Paste")
			(net "P5V_STBY")
		)
		(pad "5" smd rect
			(at -2.39522 -0.48006 90)
			(size 0.7112 0.254)
			(layers "F.Cu" "F.Mask" "F.Paste")
			(net "GND")
		)
		(pad "6" smd rect
			(at -2.39522 -0.029972 90)
			(size 0.7112 0.254)
			(layers "F.Cu" "F.Mask" "F.Paste")
			(net "TP_PVCCINC_CPU1_PH1_GL_0")
		)
		(pad "7" smd custom
			(at 0.016764 1.145032 90)
			(size 0.53975 0.53975)
			(layers "F.Cu" "F.Mask" "F.Paste")
			(net "GND")
			(options
				(clearance outline)
				(anchor circle)
			)
			(primitives
				(gr_poly
					(pts
						(xy -2.7051 1.0795) (xy -2.7051 -0.3683) (xy -0.9271 -0.3683) (xy -0.9271 -1.0795) (xy 2.7051 -1.0795)
						(xy 2.7051 1.0795)
					)
					(width 0)
					(fill yes)
				)
			)
		)
		(pad "10" smd rect
			(at -0.008382 2.874772 90)
			(size 4.3434 0.6096)
			(layers "F.Cu" "F.Mask" "F.Paste")
			(net "VR_PVCCIN_CPU1_PHASE1")
		)
		(pad "25" smd rect
			(at 1.548384 -1.283208 90)
			(size 2.3368 2.0066)
			(layers "F.Cu" "F.Mask" "F.Paste")
			(net "VR_FET_SW_P12V_STBY_PVCCIN_CPU1")
		)
		(pad "30" smd rect
			(at 2.050034 -2.895092 90)
			(size 0.254 0.7112)
			(layers "F.Cu" "F.Mask" "F.Paste")
			(net "VR_FET_SW_P12V_STBY_PVCCIN_CPU1")
		)
		(pad "31" smd rect
			(at 1.599946 -2.895092 90)
			(size 0.254 0.7112)
			(layers "F.Cu" "F.Mask" "F.Paste")
			(net "Net_356")
		)
		(pad "32" smd rect
			(at 1.150112 -2.895092 90)
			(size 0.254 0.7112)
			(layers "F.Cu" "F.Mask" "F.Paste")
			(net "VR_PVCCIN_CPU1_PH1_PHASE")
		)
		(pad "33" smd rect
			(at 0.700024 -2.895092 90)
			(size 0.254 0.7112)
			(layers "F.Cu" "F.Mask" "F.Paste")
			(net "VR_PVCCIN_CPU1_PH1_BOOT_R")
		)
		(pad "34" smd rect
			(at 0.249936 -2.895092 90)
			(size 0.254 0.7112)
			(layers "F.Cu" "F.Mask" "F.Paste")
			(net "VR_PVCCIN_CPU1_PWM1")
		)
		(pad "35" smd rect
			(at -0.199898 -2.895092 90)
			(size 0.254 0.7112)
			(layers "F.Cu" "F.Mask" "F.Paste")
			(net "P5V_STBY")
		)
		(pad "36" smd rect
			(at -0.649986 -2.895092 90)
			(size 0.254 0.7112)
			(layers "F.Cu" "F.Mask" "F.Paste")
			(net "A_TSENSE_PVCCIN_CPU1")
		)
		(pad "37" smd rect
			(at -1.100074 -2.895092 90)
			(size 0.254 0.7112)
			(layers "F.Cu" "F.Mask" "F.Paste")
			(net "VR_PVCCIN_CPU1_PH1_OCSET")
		)
		(pad "38" smd rect
			(at -1.549908 -2.895092 90)
			(size 0.254 0.7112)
			(layers "F.Cu" "F.Mask" "F.Paste")
			(net "ISENSE_PVCCIN_CPU1_PH1_IMON")
		)
		(pad "39" smd rect
			(at -1.999996 -2.895092 90)
			(size 0.254 0.7112)
			(layers "F.Cu" "F.Mask" "F.Paste")
			(net "VR_PVCCIN_CPU1_AIREF1")
		)
		(pad "40" smd rect
			(at -0.871728 -1.283208 90)
			(size 1.8034 2.0066)
			(layers "F.Cu" "F.Mask" "F.Paste")
			(net "GND")
		)
		(pad "41" smd rect
			(at -1.533906 0.247904 90)
			(size 0.508 0.3556)
			(layers "F.Cu" "F.Mask" "F.Paste")
			(net "TP_PVCCINC_CPU1_PH1_GL_1")
		)
	)
)
